# T6G (Grand Teton) — schematic netlist excerpt (pin names and nets, part order shuffled) for the footprints in the layout excerpt that follows; sources: Cadence DE-HDL packaged netlist, KiCad conversion of 04192023_DAF0TMB3IC0_F0TG_MB_C_brd_V02_OCP.brd

C1879  Q_CAP  0.1UF 25V 10% X7R  pkg 0402  page 143 : A = P3V3_AUX ; B = GND
R6193  Q_RES  0 5% CHIP  pkg 0201LF  page 180 : A = USB2_CPU0_P0_DN ; B = USB2_CPU0_P0_R2_DN

Q134  MOSFET_NCH_DUAL  PJT138K IC  pkg SOT363XD  page 125
  S1  = GND
  G1  = PRSNT_CABLE_GPU_A1_N
  D2  = PRSNT_CABLE_GPU_A1_ISO_N
  S2  = GND
  G2  = PRSNT_CABLE_GPU_A1
  D1  = PRSNT_CABLE_GPU_A1

(kicad_pcb
	(version 20260206)
	(generator "pcbnew")
	(generator_version "10.0")
	(general
		(thickness 1.6)
		(legacy_teardrops no)
	)
	(paper "A4")
	(title_block
		(title "04192023_DAF0TMB3IC0_F0TG_MB_C_brd_V02_OCP.brd")
		(comment 1 "Grand Teton / footprints 2723-2725 of 8354")
	)
	(layers
		(0 "F.Cu" signal "TOP")
		(4 "In1.Cu" signal "GND")
		(6 "In2.Cu" signal "IN1")
		(8 "In3.Cu" signal "GND1")
		(10 "In4.Cu" signal "IN2")
		(12 "In5.Cu" signal "GND2")
		(14 "In6.Cu" signal "IN3")
		(16 "In7.Cu" signal "GND3")
		(18 "In8.Cu" signal "VCC")
		(20 "In9.Cu" signal "VCC1")
		(22 "In10.Cu" signal "GND4")
		(24 "In11.Cu" signal "IN4")
		(26 "In12.Cu" signal "GND5")
		(28 "In13.Cu" signal "IN5")
		(30 "In14.Cu" signal "GND6")
		(32 "In15.Cu" signal "IN6")
		(34 "In16.Cu" signal "GND7")
		(2 "B.Cu" signal "BOTTOM")
		(9 "F.Adhes" user "F.Adhesive")
		(11 "B.Adhes" user "B.Adhesive")
		(13 "F.Paste" user "Package Geometry/Pastemask Top")
		(15 "B.Paste" user "Package Geometry/Pastemask Bottom")
		(5 "F.SilkS" user "Ref Des/Silkscreen Top")
		(7 "B.SilkS" user "Ref Des/Silkscreen Bottom")
		(1 "F.Mask" user "Board Geometry/Soldermask Top")
		(3 "B.Mask" user "Board Geometry/Soldermask Bottom")
		(17 "Dwgs.User" user "User.Drawings")
		(19 "Cmts.User" user "User.Comments")
		(21 "Eco1.User" user "User.Eco1")
		(23 "Eco2.User" user "User.Eco2")
		(25 "Edge.Cuts" user "Board Geometry/Outline")
		(27 "Margin" user)
		(31 "F.CrtYd" user "Package Geometry/Place Bound Top")
		(29 "B.CrtYd" user "Package Geometry/Place Bound Bottom")
		(35 "F.Fab" user "Ref Des/Assembly Top")
		(33 "B.Fab" user "Ref Des/Assembly Bottom")
	)
	(footprint ""
		(layer "F.Cu")
		(at 356.234746 -416.145218 90)
		(property "Reference" "Q134"
			(at -1.4224 -2.44348 90)
			(unlocked yes)
			(layer "F.SilkS")
			(effects
				(font
					(size 0.7874 0.5842)
					(thickness 0.1524)
				)
				(justify left)
			)
		)
		(property "Value" ""
			(at 0 0 90)
			(layer "F.Fab")
			(effects
				(font
					(size 1.27 1.27)
				)
			)
		)
		(duplicate_pad_numbers_are_jumpers no)
		(fp_line
			(start 1.332738 -1.100074)
			(end 1.332738 1.100074)
			(stroke
				(width 0.1524)
				(type default)
			)
			(layer "F.SilkS")
		)
		(fp_line
			(start 0.4826 -1.100074)
			(end 1.332738 -1.100074)
			(stroke
				(width 0.1524)
				(type default)
			)
			(layer "F.SilkS")
		)
		(fp_line
			(start -0.4826 -1.100074)
			(end 0 -0.541274)
			(stroke
				(width 0.1524)
				(type default)
			)
			(layer "F.SilkS")
		)
		(fp_line
			(start -1.332738 -1.100074)
			(end -0.4826 -1.100074)
			(stroke
				(width 0.1524)
				(type default)
			)
			(layer "F.SilkS")
		)
		(fp_line
			(start 0 -0.541274)
			(end 0.4826 -1.100074)
			(stroke
				(width 0.1524)
				(type default)
			)
			(layer "F.SilkS")
		)
		(fp_line
			(start 1.332738 1.100074)
			(end -1.332738 1.100074)
			(stroke
				(width 0.1524)
				(type default)
			)
			(layer "F.SilkS")
		)
		(fp_line
			(start -1.332738 1.100074)
			(end -1.332738 -1.100074)
			(stroke
				(width 0.1524)
				(type default)
			)
			(layer "F.SilkS")
		)
		(fp_poly
			(pts
				(xy -1.489456 -1.189482) (xy -2.23393 -1.43764) (xy -1.737614 -1.933956)
			)
			(stroke
				(width 0)
				(type default)
			)
			(fill yes)
			(layer "F.SilkS")
		)
		(fp_line
			(start 0.674878 -1.100074)
			(end 0.674878 1.100074)
			(stroke
				(width 0.1)
				(type default)
			)
			(layer "F.Fab")
		)
		(fp_line
			(start -0.674878 -1.100074)
			(end 0.674878 -1.100074)
			(stroke
				(width 0.1)
				(type default)
			)
			(layer "F.Fab")
		)
		(fp_line
			(start 0.674878 1.100074)
			(end -0.674878 1.100074)
			(stroke
				(width 0.1)
				(type default)
			)
			(layer "F.Fab")
		)
		(fp_line
			(start -0.674878 1.100074)
			(end -0.674878 -1.100074)
			(stroke
				(width 0.1)
				(type default)
			)
			(layer "F.Fab")
		)
		(fp_poly
			(pts
				(xy -2.2352 -0.298958) (xy -2.2352 -1.001014) (xy -1.533144 -0.649986)
			)
			(stroke
				(width 0)
				(type default)
			)
			(fill yes)
			(layer "F.Fab")
		)
		(pad "1" smd rect
			(at -0.94996 -0.649986 180)
			(size 0.4318 0.508)
			(layers "F.Cu" "F.Mask" "F.Paste")
			(net "GND")
		)
		(pad "2" smd rect
			(at -0.94996 0 180)
			(size 0.4318 0.508)
			(layers "F.Cu" "F.Mask" "F.Paste")
			(net "PRSNT_CABLE_GPU_A1_N")
		)
		(pad "3" smd rect
			(at -0.94996 0.649986 180)
			(size 0.4318 0.508)
			(layers "F.Cu" "F.Mask" "F.Paste")
			(net "PRSNT_CABLE_GPU_A1_ISO_N")
		)
		(pad "4" smd rect
			(at 0.94996 0.649986 180)
			(size 0.4318 0.508)
			(layers "F.Cu" "F.Mask" "F.Paste")
			(net "GND")
		)
		(pad "5" smd rect
			(at 0.94996 0 180)
			(size 0.4318 0.508)
			(layers "F.Cu" "F.Mask" "F.Paste")
			(net "PRSNT_CABLE_GPU_A1")
		)
		(pad "6" smd rect
			(at 0.94996 -0.649986 180)
			(size 0.4318 0.508)
			(layers "F.Cu" "F.Mask" "F.Paste")
			(net "PRSNT_CABLE_GPU_A1")
		)
	)
	(footprint ""
		(layer "F.Cu")
		(at 147.16379 -96.012508 90)
		(property "Reference" "C1879"
			(at 0 0 90)
			(layer "F.SilkS")
			(hide yes)
			(effects
				(font
					(size 1.27 1.27)
				)
			)
		)
		(property "Value" ""
			(at 0 0 90)
			(layer "F.Fab")
			(effects
				(font
					(size 1.27 1.27)
				)
			)
		)
		(duplicate_pad_numbers_are_jumpers no)
		(fp_line
			(start 0.7874 -0.4064)
			(end 0.7874 0.4064)
			(stroke
				(width 0.1524)
				(type default)
			)
			(layer "F.SilkS")
		)
		(fp_line
			(start -0.7874 -0.4064)
			(end 0.7874 -0.4064)
			(stroke
				(width 0.1524)
				(type default)
			)
			(layer "F.SilkS")
		)
		(fp_line
			(start 0.7874 0.4064)
			(end -0.7874 0.4064)
			(stroke
				(width 0.1524)
				(type default)
			)
			(layer "F.SilkS")
		)
		(fp_line
			(start -0.7874 0.4064)
			(end -0.7874 -0.4064)
			(stroke
				(width 0.1524)
				(type default)
			)
			(layer "F.SilkS")
		)
		(fp_line
			(start -0.12065 -0.305054)
			(end -0.12065 -0.2794)
			(stroke
				(width 0.1)
				(type default)
			)
			(layer "F.Fab")
		)
		(fp_line
			(start -0.67945 -0.305054)
			(end -0.12065 -0.305054)
			(stroke
				(width 0.1)
				(type default)
			)
			(layer "F.Fab")
		)
		(fp_line
			(start 0.67945 -0.3048)
			(end 0.67945 0.3048)
			(stroke
				(width 0.1)
				(type default)
			)
			(layer "F.Fab")
		)
		(fp_line
			(start 0.12065 -0.3048)
			(end 0.67945 -0.3048)
			(stroke
				(width 0.1)
				(type default)
			)
			(layer "F.Fab")
		)
		(fp_line
			(start 0.12065 -0.2794)
			(end 0.12065 -0.3048)
			(stroke
				(width 0.1)
				(type default)
			)
			(layer "F.Fab")
		)
		(fp_line
			(start -0.12065 -0.2794)
			(end 0.12065 -0.2794)
			(stroke
				(width 0.1)
				(type default)
			)
			(layer "F.Fab")
		)
		(fp_line
			(start 0.120396 0.2794)
			(end -0.12065 0.2794)
			(stroke
				(width 0.1)
				(type default)
			)
			(layer "F.Fab")
		)
		(fp_line
			(start -0.12065 0.2794)
			(end -0.12065 0.3048)
			(stroke
				(width 0.1)
				(type default)
			)
			(layer "F.Fab")
		)
		(fp_line
			(start 0.67945 0.3048)
			(end 0.120396 0.3048)
			(stroke
				(width 0.1)
				(type default)
			)
			(layer "F.Fab")
		)
		(fp_line
			(start 0.120396 0.3048)
			(end 0.120396 0.2794)
			(stroke
				(width 0.1)
				(type default)
			)
			(layer "F.Fab")
		)
		(fp_line
			(start -0.12065 0.3048)
			(end -0.67945 0.3048)
			(stroke
				(width 0.1)
				(type default)
			)
			(layer "F.Fab")
		)
		(fp_line
			(start -0.67945 0.3048)
			(end -0.67945 -0.305054)
			(stroke
				(width 0.1)
				(type default)
			)
			(layer "F.Fab")
		)
		(pad "1" smd circle
			(at -0.40005 0 90)
			(size 0 0)
			(layers "F.Cu" "F.Mask" "F.Paste")
			(net "P3V3_AUX")
		)
		(pad "2" smd circle
			(at 0.40005 0 90)
			(size 0 0)
			(layers "F.Cu" "F.Mask" "F.Paste")
			(net "GND")
		)
	)
	(footprint ""
		(layer "F.Cu")
		(at 131.64058 -26.99258 -90)
		(property "Reference" "R6193"
			(at 0 0 270)
			(layer "F.SilkS")
			(hide yes)
			(effects
				(font
					(size 1.27 1.27)
				)
			)
		)
		(property "Value" ""
			(at 0 0 270)
			(layer "F.Fab")
			(effects
				(font
					(size 1.27 1.27)
				)
			)
		)
		(duplicate_pad_numbers_are_jumpers no)
		(fp_line
			(start -0.32512 0.175006)
			(end -0.32512 -0.175006)
			(stroke
				(width 0.1)
				(type default)
			)
			(layer "F.Fab")
		)
		(fp_line
			(start 0.32512 0.175006)
			(end -0.32512 0.175006)
			(stroke
				(width 0.1)
				(type default)
			)
			(layer "F.Fab")
		)
		(fp_line
			(start -0.32512 -0.175006)
			(end 0.32512 -0.175006)
			(stroke
				(width 0.1)
				(type default)
			)
			(layer "F.Fab")
		)
		(fp_line
			(start 0.32512 -0.175006)
			(end 0.32512 0.175006)
			(stroke
				(width 0.1)
				(type default)
			)
			(layer "F.Fab")
		)
		(pad "1" smd rect
			(at -0.2667 0 270)
			(size 0.3048 0.381)
			(layers "F.Cu" "F.Mask" "F.Paste")
			(net "USB2_CPU0_P0_DN")
		)
		(pad "2" smd rect
			(at 0.2667 0 90)
			(size 0.3048 0.381)
			(layers "F.Cu" "F.Mask" "F.Paste")
			(net "USB2_CPU0_P0_R2_DN")
		)
	)
)
